FILE_TYPE = CONNECTIVITY;
{Allegro Design Entry HDL 17.4-2019 S026 (4007227) 1/17/2022}
"PAGE_NUMBER" = 344;
0"NC";
1"GND\g";
2"GND\g";
3"P3V3_AUX\g";
4"P3V3_AUX\g";
5"GND\g";
6"GND\g";
7"GND\g";
8"GND\g";
9"GND\g";
10"GND\g";
11"GND\g";
12"P3V3_OCP_V3_2_R\g";
13"P12V_AUX\g";
14"P12V_OCP_V3_2\g";
15"P12V_OCP_AVIN_PD_2";
16"P12V_OCP_OV_FB_2";
17"HP_LVC3_OCP_V3_2_P12V_PWRGD";
18"P12V_OCP_FLTB_2";
19"P12V_OCP_IMON_2";
20"P12V_OCP_V3_2_EN_2_R3";
21"GND\g";
22"P12V_OCP_TIMER_2";
23"P12V_OCP_ISET_2";
24"P12V_OCP_SS_2";
25"GND\g";
26"GND\g";
27"GND\g";
28"GND\g";
29"P12V_AUX\g";
30"P3V3_AUX\g";
31"GND\g";
32"P12V_OCP_V3_2_ISENSE_MPS_TIC";
33"P12V_OCP_V3_2_ISENSE_MPS_MAM";
34"P12V_OCP_AVIN_PD_2";
35"P3V3_OCP_MODE_2";
36"P12V_OCP_V3_2_BUF_EN_R";
37"P3V3_OCP_EN_2";
38"HP_LVC3_OCP_V3_2_P12V_PWRGD";
39"P3V3_OCP_V3_2_EN_R";
40"P12V_OCP_V3_2_EN_R";
41"P12V_OCP_V3_2_BUF_EN_R";
42"P3V3_OCP_ILIMIT_2";
43"P3V3_OCP_DVDT_2";
44"P3V3_OCP_GATE_PU207_2";
%"GND"
"1","(-3600,2250)","0","pure_quanta_power","I1";
;
CDS_LIB"pure_quanta_power"
SIZE"1B"
HDL_POWER"GND";
"A<SIZE-1..0>\NAC"1;
%"GND"
"1","(-3200,2800)","0","pure_quanta_power","I11";
;
CDS_LIB"pure_quanta_power"
SIZE"1B"
HDL_POWER"GND";
"A<SIZE-1..0>\NAC"21;
%"GND"
"1","(-2925,3175)","0","pure_quanta_power","I12";
;
CDS_LIB"pure_quanta_power"
SIZE"1B"
HDL_POWER"GND";
"A<SIZE-1..0>\NAC"2;
%"Q_CAP"
"1","(-2925,3550)","0","pure_quanta","I13";
;
LOCATION"PC2165"
$SEC"1"
CDS_SEC"1"
PACK_TYPE"C0402"
MATERIAL"X6S"
VALUE"1UF"
VOLTAGE"25V"
ROOM"NIC_P12V_MPS_MAM_BOM2"
TOLERANCE"10%"
CDS_LIB"pure_quanta"
PART_NUMBER"CH5104KEB02";
"B"
$PN"2"2;
"A"
$PN"1"13;
%"UNIVERSAL_POWER"
"1","(-2925,3975)","0","pure_quanta_power","I14";
;
HDL_POWER"P12V_AUX"
CDS_LIB"pure_quanta_power";
"A"13;
%"Q_RES"
"2","(-1425,2200)","0","pure_quanta","I15";
;
LOCATION"PR3849"
$SEC"1"
CDS_SEC"1"
VALUE"17.4K"
ROOM"NIC_P12V_MPS_MAM_BOM2"
MATERIAL"CHIP"
TOLERANCE"1%"
WATTAGE"1/16W"
PACK_TYPE"0402LF"
CDS_LIB"pure_quanta"
PART_NUMBER"CS31742FB04";
"A"
$PN"1"19;
"B"
$PN"2"26;
%"GND"
"1","(-975,1825)","0","pure_quanta_power","I16";
;
SIZE"1B"
CDS_LIB"pure_quanta_power"
HDL_POWER"GND";
"A<SIZE-1..0>\NAC"26;
%"Q_RES"
"1","(-850,2550)","0","pure_quanta","I18";
;
LOCATION"PR3851"
$SEC"1"
CDS_SEC"1"
ROOM"NIC_P12V_MPS_MAM_BOM2"
WATTAGE"1/16W"
VALUE"10K"
TOLERANCE"1%"
MATERIAL"CHIP"
PACK_TYPE"0402LF"
CDS_LIB"pure_quanta"
PART_NUMBER"CS31002FB08";
"B"
$PN"2"3;
"A"
$PN"1"18;
%"VCCAUX15"
"1","(-580,2608)","0","pure_quanta_power","I19";
;
HDL_POWER"P3V3_AUX"
CDS_LIB"pure_quanta_power";
"A"3;
%"Q_CAP"
"1","(-3600,2600)","0","pure_quanta","I2";
;
LOCATION"PC2164"
$SEC"1"
CDS_SEC"1"
ROOM"NIC_P12V_MPS_MAM_BOM2"
PACK_TYPE"0402"
VALUE"0.22UF"
VOLTAGE"16V"
MATERIAL"X7R"
TOLERANCE"10%"
CDS_LIB"pure_quanta"
PART_NUMBER"CH4223K1B00";
"B"
$PN"2"1;
"A"
$PN"1"22;
%"Q_RES"
"2","(20,2533)","0","pure_quanta","I20";
;
LOCATION"PR3854"
$SEC"1"
CDS_SEC"1"
PACK_TYPE"0402LF"
ROOM"NIC_P12V_MPS_MAM_BOM2"
MATERIAL"CHIP"
WATTAGE"1/16W"
TOLERANCE"1%"
VALUE"10K"
CDS_LIB"pure_quanta"
PART_NUMBER"CS31002FB08";
"A"
$PN"1"16;
"B"
$PN"2"27;
%"GND"
"1","(220,2208)","0","pure_quanta_power","I21";
;
SIZE"1B"
CDS_LIB"pure_quanta_power"
HDL_POWER"GND";
"A<SIZE-1..0>\NAC"27;
%"Q_RES"
"1","(425,1950)","0","pure_quanta","I22";
;
LOCATION"R3874"
$SEC"1"
CDS_SEC"1"
ROOM"NIC_P12V_MPS_TIC_BOM3"
PACK_TYPE"0402LF"
TOLERANCE"5%"
VALUE"0"
MATERIAL"EMPTY"
WATTAGE"1/16W"
CDS_LIB"pure_quanta"
PART_NUMBER"CS00002JB13";
"B"
$PN"2"32;
"A"
$PN"1"19;
%"Q_RES"
"1","(425,2075)","0","pure_quanta","I23";
;
LOCATION"R3873"
$SEC"1"
CDS_SEC"1"
WATTAGE"1/16W"
PACK_TYPE"0402LF"
TOLERANCE"5%"
ROOM"NIC_P12V_MPS_MAM_BOM2"
VALUE"0"
MATERIAL"CHIP"
CDS_LIB"pure_quanta"
PART_NUMBER"CS00002JB13";
"B"
$PN"2"33;
"A"
$PN"1"19;
%"Q_CAP"
"1","(550,2525)","0","pure_quanta","I24";
;
LOCATION"PC1320"
$SEC"1"
CDS_SEC"1"
ROOM"NIC_P12V_MPS_MAM_BOM2"
PACK_TYPE"C0603"
MATERIAL"X7R"
VALUE"2.2UF"
VOLTAGE"16V"
TOLERANCE"20%"
CDS_LIB"pure_quanta"
PART_NUMBER"CH5223M1900";
"B"
$PN"2"27;
"A"
$PN"1"34;
%"Q_RES"
"2","(-1475,3600)","0","pure_quanta","I27";
;
LOCATION"R3848"
$SEC"1"
CDS_SEC"1"
PACK_TYPE"0402LF"
VALUE"10K"
MATERIAL"CHIP"
ROOM"NIC_P12V_MPS_MAM_BOM2"
WATTAGE"1/16W"
TOLERANCE"1%"
CDS_LIB"pure_quanta"
PART_NUMBER"CS31002FB08";
"A"
$PN"1"4;
"B"
$PN"2"17;
%"VCCAUX15"
"1","(-1475,3825)","0","pure_quanta_power","I28";
;
HDL_POWER"P3V3_AUX"
CDS_LIB"pure_quanta_power";
"A"4;
%"GND"
"1","(-3175,2175)","0","pure_quanta_power","I3";
;
SIZE"1B"
CDS_LIB"pure_quanta_power"
HDL_POWER"GND";
"A<SIZE-1..0>\NAC"5;
%"Q_RES"
"2","(-925,3025)","0","pure_quanta","I30";
;
LOCATION"PR3850"
$SEC"1"
CDS_SEC"1"
ROOM"NIC_P12V_MPS_MAM_BOM2"
PACK_TYPE"0402LF"
MATERIAL"EMPTY"
VALUE"100"
WATTAGE"1/16W"
TOLERANCE"1%"
CDS_LIB"pure_quanta"
PART_NUMBER"CS11002FB07";
"A"
$PN"1"14;
"B"
$PN"2"15;
%"Q_RES"
"2","(-375,3025)","0","pure_quanta","I31";
;
LOCATION"PR3852"
$SEC"1"
CDS_SEC"1"
MATERIAL"EMPTY"
PACK_TYPE"0402LF"
TOLERANCE"1%"
VALUE"71.5K"
ROOM"NIC_P12V_MPS_MAM_BOM2"
WATTAGE"1/16W"
CDS_LIB"pure_quanta"
PART_NUMBER"CS37152FB05";
"A"
$PN"1"14;
"B"
$PN"2"16;
%"UNIVERSAL_GND"
"1","(-250,5875)","0","pure_quanta_power","I34";
;
CDS_LIB"pure_quanta_power"
HDL_POWER"GND";
"A"28;
%"Q_CAP"
"1","(-250,6175)","0","pure_quanta","I35";
;
LOCATION"PC2168"
$SEC"1"
CDS_SEC"1"
ROOM"NIC_P3V3_BOM2"
VALUE"39PF"
MATERIAL"NPO"
VOLTAGE"50V"
PACK_TYPE"0402"
CDS_LIB"pure_quanta"
TOLERANCE"5%"
PART_NUMBER"CH03906JB06";
"B"
$PN"2"28;
"A"
$PN"1"35;
%"Q_RES"
"2","(20,2958)","0","pure_quanta","I36";
;
LOCATION"PR3853"
$SEC"1"
CDS_SEC"1"
PACK_TYPE"0402LF"
WATTAGE"1/16W"
MATERIAL"CHIP"
VALUE"120K"
TOLERANCE"1%"
ROOM"NIC_P12V_MPS_MAM_BOM2"
CDS_LIB"pure_quanta"
PART_NUMBER"CS41202FB05";
"A"
$PN"1"29;
"B"
$PN"2"16;
%"Q_RES"
"2","(550,2950)","0","pure_quanta","I37";
;
LOCATION"PR3857"
$SEC"1"
CDS_SEC"1"
MATERIAL"CHIP"
ROOM"NIC_P12V_MPS_MAM_BOM2"
PACK_TYPE"0603LF"
WATTAGE"1/10W"
VALUE"49.9"
TOLERANCE"1%"
CDS_LIB"pure_quanta"
PART_NUMBER"CS04993F909";
"A"
$PN"1"29;
"B"
$PN"2"34;
%"UNIVERSAL_POWER"
"1","(500,3225)","0","pure_quanta_power","I38";
;
HDL_POWER"P12V_AUX"
CDS_LIB"pure_quanta_power";
"A"29;
%"GND"
"1","(1050,2950)","0","pure_quanta_power","I39";
;
CDS_LIB"pure_quanta_power"
SIZE"1B"
HDL_POWER"GND";
"A<SIZE-1..0>\NAC"6;
%"Q_RES"
"2","(-3175,2450)","0","pure_quanta","I4";
;
LOCATION"PR3847"
$SEC"1"
CDS_SEC"1"
MATERIAL"CHIP"
ROOM"NIC_P12V_MPS_MAM_BOM2"
PACK_TYPE"0402LF"
VALUE"14.3K"
TOLERANCE"1%"
WATTAGE"1/16W"
CDS_LIB"pure_quanta"
PART_NUMBER"CS31432FB02";
"A"
$PN"1"23;
"B"
$PN"2"5;
%"Q_CAP"
"1","(1050,3200)","2","pure_quanta","I40";
;
LOCATION"PC2174"
$SEC"1"
CDS_SEC"1"
ROOM"NIC_P12V_MPS_MAM_BOM2"
VOLTAGE"25V"
MATERIAL"X7R"
PACK_TYPE"0402"
VALUE"0.1UF"
TOLERANCE"10%"
CDS_LIB"pure_quanta"
PART_NUMBER"CH4104K1B00";
"B"
$PN"2"6;
"A"
$PN"1"14;
%"UNIVERSAL_POWER"
"1","(1050,3500)","2","pure_quanta_power","I41";
;
HDL_POWER"P12V_OCP_V3_2"
CDS_LIB"pure_quanta_power";
"A"14;
%"Q_RES"
"2","(150,6175)","0","pure_quanta","I43";
;
LOCATION"PR3855"
$SEC"1"
CDS_SEC"1"
ROOM"NIC_P3V3_BOM2"
MATERIAL"CHIP"
VALUE"71.5K"
PACK_TYPE"0402LF"
TOLERANCE"1%"
CDS_LIB"pure_quanta"
WATTAGE"1/16W"
PART_NUMBER"CS37152FB05";
"A"
$PN"1"35;
"B"
$PN"2"28;
%"UNIVERSAL_GND"
"1","(495,5883)","0","pure_quanta_power","I45";
;
CDS_LIB"pure_quanta_power"
HDL_POWER"GND";
"A"7;
%"Q_RES"
"1","(495,6158)","1","pure_quanta","I46";
;
LOCATION"PR3856"
$SEC"1"
CDS_SEC"1"
PACK_TYPE"0402LF"
MATERIAL"CHIP"
ROOM"NIC_P3V3_BOM2"
VALUE"1.33K"
TOLERANCE"1%"
CDS_LIB"pure_quanta"
WATTAGE"1/16W"
PART_NUMBER"CS21332FB05";
"B"
$PN"2"42;
"A"
$PN"1"7;
%"UNIVERSAL_GND"
"1","(750,6550)","0","pure_quanta_power","I47";
;
CDS_LIB"pure_quanta_power"
HDL_POWER"GND";
"A"8;
%"Q_CAP"
"1","(750,6750)","0","pure_quanta","I48";
;
LOCATION"PC2169"
$SEC"1"
CDS_SEC"1"
VALUE"1UF"
ROOM"NIC_P3V3_BOM2"
VOLTAGE"25V"
MATERIAL"X6S"
TOLERANCE"10%"
PACK_TYPE"C0402"
CDS_LIB"pure_quanta"
PART_NUMBER"CH5104KEB02";
"B"
$PN"2"8;
"A"
$PN"1"30;
%"UNIVERSAL_GND"
"1","(870,5883)","0","pure_quanta_power","I49";
;
CDS_LIB"pure_quanta_power"
HDL_POWER"GND";
"A"9;
%"GND"
"1","(-2755,2133)","0","pure_quanta_power","I5";
;
SIZE"1B"
CDS_LIB"pure_quanta_power"
HDL_POWER"GND";
"A<SIZE-1..0>\NAC"10;
%"Q_CAP"
"1","(870,6108)","0","pure_quanta","I50";
;
LOCATION"PC1321"
$SEC"1"
CDS_SEC"1"
VALUE"0.068UF"
VOLTAGE"16V"
ROOM"NIC_P3V3_BOM2"
MATERIAL"X7R"
PACK_TYPE"0402"
TOLERANCE"10%"
CDS_LIB"pure_quanta"
PART_NUMBER"CH3683K1B09";
"B"
$PN"2"9;
"A"
$PN"1"43;
%"MP5016GQHLZ"
"1","(1675,6425)","0","pure_quanta","I51";
;
LOCATION"PU207"
$SEC"1"
CDS_SEC"1"
VALUE"MP5016GQH-L-Z"
ROOM"NIC_P3V3_BOM2"
PART_TYPE"SMLF"
MATERIAL"IC"
CDS_LIB"pure_quanta"
CDS_LMAN_SYM_OUTLINE"-250,200,250,-200"
NEEDS_NO_SIZE"TRUE"
PART_NUMBER"AL005016007";
"SOURCE"
$PN"6_7"12;
"GATE"
$PN"8"44;
"DV_DT"
$PN"10"43;
"VCC"
$PN"1_2"30;
"GND"
$PN"3"31;
"ILIMIT"
$PN"4"42;
"MODE"
$PN"5"35;
"EN"
$PN"9"37;
%"UNIVERSAL_POWER"
"1","(825,7125)","2","pure_quanta_power","I52";
;
HDL_POWER"P3V3_AUX"
CDS_LIB"pure_quanta_power";
"A"30;
%"UNIVERSAL_GND"
"1","(2500,5800)","0","pure_quanta_power","I53";
;
CDS_LIB"pure_quanta_power"
HDL_POWER"GND";
"A"31;
%"Q_CAP"
"1","(2500,6150)","0","pure_quanta","I54";
;
LOCATION"PC1322"
$SEC"1"
CDS_SEC"1"
ROOM"NIC_P3V3_BOM2"
MATERIAL"X7R"
PACK_TYPE"0402"
VOLTAGE"50V"
VALUE"100PF"
TOLERANCE"5%"
CDS_LIB"pure_quanta"
PART_NUMBER"CH11006JB18";
"B"
$PN"2"31;
"A"
$PN"1"44;
%"UNIVERSAL_GND"
"1","(2900,6000)","0","pure_quanta_power","I55";
;
CDS_LIB"pure_quanta_power"
HDL_POWER"GND";
"A"11;
%"Q_CAP"
"1","(2900,6350)","0","pure_quanta","I56";
;
LOCATION"PC2173"
$SEC"1"
CDS_SEC"1"
VALUE"10UF"
VOLTAGE"16V"
TOLERANCE"10%"
ROOM"NIC_P3V3_BOM2"
MATERIAL"X6S"
PACK_TYPE"C0805"
CDS_LIB"pure_quanta"
PART_NUMBER"CH6103KEA01";
"B"
$PN"2"11;
"A"
$PN"1"12;
%"UNIVERSAL_POWER"
"1","(2900,6900)","2","pure_quanta_power","I57";
;
HDL_POWER"P3V3_OCP_V3_2_R"
CDS_LIB"pure_quanta_power";
"A"12;
%"Q_CAP"
"1","(-975,2200)","0","pure_quanta","I58";
;
LOCATION"PC2167"
$SEC"1"
CDS_SEC"1"
VALUE"100PF"
ROOM"NIC_P12V_MPS_MAM_BOM2"
VOLTAGE"50V"
TOLERANCE"5%"
MATERIAL"NPO"
PACK_TYPE"0402"
CDS_LIB"pure_quanta"
PART_NUMBER"CH11006JB00";
"B"
$PN"2"26;
"A"
$PN"1"19;
%"Q_CAP"
"1","(-2755,2383)","0","pure_quanta","I6";
;
LOCATION"PC2166"
$SEC"1"
CDS_SEC"1"
ROOM"NIC_P12V_MPS_MAM_BOM2"
MATERIAL"X7R"
VALUE"0.047UF"
PACK_TYPE"C0402"
VOLTAGE"25V"
TOLERANCE"10%"
CDS_LIB"pure_quanta"
PART_NUMBER"CH3474K1B04";
"B"
$PN"2"10;
"A"
$PN"1"24;
%"GND"
"1","(-2434,2316)","0","pure_quanta_power","I7";
;
CDS_LIB"pure_quanta_power"
SIZE"1B"
HDL_POWER"GND";
"A<SIZE-1..0>\NAC"25;
%"Q_RES"
"1","(-3500,3050)","0","pure_quanta","I73";
;
LOCATION"R3630"
$SEC"1"
CDS_SEC"1"
ROOM"NIC_P12V_MPS_MAM_BOM2"
TOLERANCE"5%"
VALUE"0"
MATERIAL"EMPTY"
CDS_LIB"pure_quanta"
PACK_TYPE"0402LF"
WATTAGE"1/16W"
PART_NUMBER"CS00002JB13";
"B"
$PN"2"20;
"A"
$PN"1"40;
%"Q_RES"
"1","(225,6475)","0","pure_quanta","I74";
;
LOCATION"R3631"
$SEC"1"
CDS_SEC"1"
ROOM"NIC_P3V3_BOM2"
TOLERANCE"5%"
VALUE"0"
MATERIAL"EMPTY"
WATTAGE"1/16W"
PACK_TYPE"0402LF"
CDS_LIB"pure_quanta"
PART_NUMBER"CS00002JB13";
"B"
$PN"2"37;
"A"
$PN"1"39;
%"Q_RES"
"1","(-3450,3500)","0","pure_quanta","I76";
;
LOCATION"R1193"
$SEC"1"
CDS_SEC"1"
ROOM"NIC_P12V_MPS_MAM_BOM2"
MATERIAL"CHIP"
VALUE"0"
TOLERANCE"5%"
PACK_TYPE"0402LF"
WATTAGE"1/16W"
CDS_LIB"pure_quanta"
PART_NUMBER"CS00002JB13";
"B"
$PN"2"20;
"A"
$PN"1"41;
%"Q_RES"
"1","(225,6850)","0","pure_quanta","I79";
;
LOCATION"R1196"
$SEC"1"
CDS_SEC"1"
MATERIAL"EMPTY"
TOLERANCE"5%"
VALUE"0"
ROOM"NIC_P3V3_BOM2"
CDS_LIB"pure_quanta"
WATTAGE"1/16W"
PACK_TYPE"0402LF"
PART_NUMBER"CS00002JB13";
"B"
$PN"2"37;
"A"
$PN"1"38;
%"Q_RES"
"1","(125,7275)","0","pure_quanta","I80";
;
LOCATION"R1521"
$SEC"1"
CDS_SEC"1"
MATERIAL"CHIP"
TOLERANCE"5%"
ROOM"NIC_P3V3_BOM2"
VALUE"0"
CDS_LIB"pure_quanta"
PACK_TYPE"0402LF"
WATTAGE"1/16W"
PART_NUMBER"CS00002JB13";
"B"
$PN"2"37;
"A"
$PN"1"36;
%"RS31312R"
"1","(-1975,2925)","0","pure_quanta","I82";
;
LOCATION"PU206"
SEC"1"
ROOM"NIC_P12V_MPS_MAM_BOM2"
VALUE"RS31312R"
PART_TYPE"SMLF"
MATERIAL"IC"
SEC_TYPE""
CDS_LIB"pure_quanta"
NEEDS_NO_SIZE"TRUE"
CDS_LMAN_SYM_OUTLINE"-250,525,250,-525"
PART_NUMBER"AL031312000";
"GND"
$PN"7"25;
"SS"
$PN"6"24;
"ISET"
$PN"5"23;
"TIMER"
$PN"4"22;
"ENTM"
$PN"3"21;
"LOADEN"
$PN"2"21;
"EN"
$PN"1"20;
"VIN_26"
$PN"26"13;
"VIN_25"
$PN"25"13;
"VIN_24"
$PN"24"13;
"VIN_23"
$PN"23"13;
"IMON"
$PN"8"19;
"FLTB"
$PN"9"18;
"PG"
$PN"10"17;
"OV"
$PN"11"16;
"VOUT_13"
$PN"13"14;
"AVIN"
$PN"12"15;
"VOUT_14"
$PN"14"14;
"VOUT_15"
$PN"15"14;
"VOUT_16"
$PN"16"14;
"VOUT_17"
$PN"17"14;
"VOUT_18"
$PN"18"14;
"VOUT_19"
$PN"19"14;
"VIN_21_22"
$PN"21_22"13;
"VOUT_20"
$PN"20"14;
END.
